(kicad_pcb
	(version 20260206)
	(generator "pcbnew")
	(generator_version "10.0")
	(general
		(thickness 1.6)
		(legacy_teardrops no)
	)
	(paper "A4")
	(title_block
		(title "netronome-mezz — pcbd0082-001_rev01_jul9_a.brd")
		(comment 1 "Open CloudServer (Microsoft) / footprint 221 of 714 (U2), pads 80-134 of 134")
	)
	(layers
		(0 "F.Cu" signal "TOP")
		(4 "In1.Cu" signal "02_GND")
		(6 "In2.Cu" signal "03_SIG")
		(8 "In3.Cu" signal "04_SIG")
		(10 "In4.Cu" signal "05_GND")
		(12 "In5.Cu" signal "06_PWR1")
		(14 "In6.Cu" signal "07_SIG")
		(16 "In7.Cu" signal "08_SIG")
		(18 "In8.Cu" signal "09_GND")
		(2 "B.Cu" signal "BOTTOM")
		(9 "F.Adhes" user "F.Adhesive")
		(11 "B.Adhes" user "B.Adhesive")
		(13 "F.Paste" user "Package Geometry/Pastemask Top")
		(15 "B.Paste" user "Package Geometry/Pastemask Bottom")
		(5 "F.SilkS" user "Ref Des/Silkscreen Top")
		(7 "B.SilkS" user "Ref Des/Silkscreen Bottom")
		(1 "F.Mask" user "Board Geometry/Soldermask Top")
		(3 "B.Mask" user "Board Geometry/Soldermask Bottom")
		(17 "Dwgs.User" user "User.Drawings")
		(19 "Cmts.User" user "User.Comments")
		(21 "Eco1.User" user "User.Eco1")
		(23 "Eco2.User" user "User.Eco2")
		(25 "Edge.Cuts" user "Board Geometry/Outline")
		(27 "Margin" user)
		(31 "F.CrtYd" user "Package Geometry/Place Bound Top")
		(29 "B.CrtYd" user "Package Geometry/Place Bound Bottom")
		(35 "F.Fab" user "Ref Des/Assembly Top")
		(33 "B.Fab" user "Ref Des/Assembly Bottom")
		(45 "User.4" user "COMPVAL_TYPE_BOTTOM")
	)
	(footprint ""
		(layer "F.Cu")
		(at 31.496 25.2984 180)
		(property "Reference" "U2"
			(at 3.81 5.84073 0)
			(unlocked yes)
			(layer "F.SilkS")
			(effects
				(font
					(size 0.7874 0.5842)
					(thickness 0.127)
				)
				(justify left)
			)
		)
		(property "Value" "*"
			(at -0.4826 -0.148209 180)
			(unlocked yes)
			(layer "F.Fab")
			(hide yes)
			(effects
				(font
					(size 1.27 0.9652)
					(thickness 0.000001)
				)
				(justify left)
			)
		)
		(property "Device Type" "PROG0057"
			(at -0.4826 -0.148209 180)
			(unlocked yes)
			(layer "F.Fab")
			(hide yes)
			(effects
				(font
					(size 1.27 0.9652)
					(thickness 0.000001)
				)
				(justify left)
			)
		)
		(duplicate_pad_numbers_are_jumpers no)
		(pad "J14" smd circle
			(at 3.250006 0.750011 180)
			(size 0.254 0.254)
			(layers "F.Cu" "F.Mask" "F.Paste")
			(net "_NC_CPLD_18")
		)
		(pad "K1" smd circle
			(at -3.250006 1.25001 180)
			(size 0.254 0.254)
			(layers "F.Cu" "F.Mask" "F.Paste")
			(net "CNTRL_SPI_MOSI")
		)
		(pad "K2" thru_hole circle
			(at -2.750007 1.25001 180)
			(size 0.3048 0.3048)
			(drill 0.127)
			(layers "*.Cu" "*.Mask")
			(remove_unused_layers no)
			(net "CNTRL_SPI_CS")
			(clearance 0.1143)
			(thermal_gap 0.1143)
			(padstack
				(mode front_inner_back)
				(layer "Inner"
					(shape circle)
					(size 0 0)
				)
				(layer "B.Cu"
					(shape circle)
					(size 0.3556 0.3556)
					(clearance 0.0889)
				)
			)
		)
		(pad "K3" smd circle
			(at -2.250008 1.25001 180)
			(size 0.254 0.254)
			(layers "F.Cu" "F.Mask" "F.Paste")
			(net "NFP_REF_CLK_100M_EN")
		)
		(pad "K12" smd circle
			(at 2.250008 1.25001 180)
			(size 0.254 0.254)
			(layers "F.Cu" "F.Mask" "F.Paste")
			(net "NFP_CFG_SPI_FLASH_HOLD_L")
		)
		(pad "K13" thru_hole circle
			(at 2.750007 1.25001 180)
			(size 0.3048 0.3048)
			(drill 0.127)
			(layers "*.Cu" "*.Mask")
			(remove_unused_layers no)
			(net "CPLD_SMBUS_ALERT_L")
			(clearance 0.1143)
			(thermal_gap 0.1143)
			(padstack
				(mode front_inner_back)
				(layer "Inner"
					(shape circle)
					(size 0 0)
				)
				(layer "B.Cu"
					(shape circle)
					(size 0.3556 0.3556)
					(clearance 0.0889)
				)
			)
		)
		(pad "K14" smd circle
			(at 3.250006 1.25001 180)
			(size 0.254 0.254)
			(layers "F.Cu" "F.Mask" "F.Paste")
			(net "NFP_CFG_SPI_FLASH_WP_L")
		)
		(pad "L1" smd circle
			(at -3.250006 1.750009 180)
			(size 0.254 0.254)
			(layers "F.Cu" "F.Mask" "F.Paste")
			(net "EXT_3.3V")
		)
		(pad "L2" thru_hole circle
			(at -2.750007 1.750009 180)
			(size 0.3048 0.3048)
			(drill 0.127)
			(layers "*.Cu" "*.Mask")
			(remove_unused_layers no)
			(net "GND")
			(clearance 0.1143)
			(thermal_gap 0.1143)
			(padstack
				(mode front_inner_back)
				(layer "Inner"
					(shape circle)
					(size 0 0)
				)
				(layer "B.Cu"
					(shape circle)
					(size 0.3556 0.3556)
					(clearance 0.0889)
				)
			)
		)
		(pad "L3" smd circle
			(at -2.250008 1.750009 180)
			(size 0.254 0.254)
			(layers "F.Cu" "F.Mask" "F.Paste")
			(net "_NC_CPLD_6")
		)
		(pad "L12" smd circle
			(at 2.250008 1.750009 180)
			(size 0.254 0.254)
			(layers "F.Cu" "F.Mask" "F.Paste")
			(net "EXT_3.3V")
		)
		(pad "L13" thru_hole circle
			(at 2.750007 1.750009 180)
			(size 0.3048 0.3048)
			(drill 0.127)
			(layers "*.Cu" "*.Mask")
			(remove_unused_layers no)
			(net "GND")
			(clearance 0.1143)
			(thermal_gap 0.1143)
			(padstack
				(mode front_inner_back)
				(layer "Inner"
					(shape circle)
					(size 0 0)
				)
				(layer "B.Cu"
					(shape circle)
					(size 0.3556 0.3556)
					(clearance 0.0889)
				)
			)
		)
		(pad "L14" smd circle
			(at 3.250006 1.750009 180)
			(size 0.254 0.254)
			(layers "F.Cu" "F.Mask" "F.Paste")
			(net "NFP_CPLD_INT_L")
		)
		(pad "M1" smd circle
			(at -3.250006 2.250008 180)
			(size 0.254 0.254)
			(layers "F.Cu" "F.Mask" "F.Paste")
			(net "NFP_REF_CLK_156M_EN")
		)
		(pad "M2" thru_hole circle
			(at -2.750007 2.250008 180)
			(size 0.3048 0.3048)
			(drill 0.127)
			(layers "*.Cu" "*.Mask")
			(remove_unused_layers no)
			(net "PCIE0_RST_L")
			(clearance 0.1143)
			(thermal_gap 0.1143)
			(padstack
				(mode front_inner_back)
				(layer "Inner"
					(shape circle)
					(size 0 0)
				)
				(layer "B.Cu"
					(shape circle)
					(size 0.3556 0.3556)
					(clearance 0.0889)
				)
			)
		)
		(pad "M3" smd circle
			(at -2.250008 2.250008 180)
			(size 0.254 0.254)
			(layers "F.Cu" "F.Mask" "F.Paste")
			(net "CPLD_GPIO_3")
		)
		(pad "M4" smd circle
			(at -1.750009 2.250008 180)
			(size 0.254 0.254)
			(layers "F.Cu" "F.Mask" "F.Paste")
			(net "NFP_SPI2_SCK")
		)
		(pad "M5" smd circle
			(at -1.25001 2.250008 180)
			(size 0.254 0.254)
			(layers "F.Cu" "F.Mask" "F.Paste")
			(net "_NC_CPLD_10")
		)
		(pad "M6" smd circle
			(at -0.750011 2.250008 180)
			(size 0.254 0.254)
			(layers "F.Cu" "F.Mask" "F.Paste")
			(net "_NC_CPLD_11")
		)
		(pad "M7" smd circle
			(at -0.250012 2.250008 180)
			(size 0.254 0.254)
			(layers "F.Cu" "F.Mask" "F.Paste")
			(net "_NC_FAN_PWM")
		)
		(pad "M8" smd circle
			(at 0.250012 2.250008 180)
			(size 0.254 0.254)
			(layers "F.Cu" "F.Mask" "F.Paste")
			(net "CPLD_GPIO_1")
		)
		(pad "M9" smd circle
			(at 0.750011 2.250008 180)
			(size 0.254 0.254)
			(layers "F.Cu" "F.Mask" "F.Paste")
			(net "CPLD_VERSION_1")
		)
		(pad "M10" smd circle
			(at 1.25001 2.250008 180)
			(size 0.254 0.254)
			(layers "F.Cu" "F.Mask" "F.Paste")
			(net "NFP_FAIL_SAFE_BOOT_L")
		)
		(pad "M11" smd circle
			(at 1.750009 2.250008 180)
			(size 0.254 0.254)
			(layers "F.Cu" "F.Mask" "F.Paste")
			(net "_NC_CPLD_14")
		)
		(pad "M12" smd circle
			(at 2.250008 2.250008 180)
			(size 0.254 0.254)
			(layers "F.Cu" "F.Mask" "F.Paste")
			(net "_NC_CPLD_17")
		)
		(pad "M13" thru_hole circle
			(at 2.750007 2.250008 180)
			(size 0.3048 0.3048)
			(drill 0.127)
			(layers "*.Cu" "*.Mask")
			(remove_unused_layers no)
			(net "_NFP_CLK_NRESET_L")
			(clearance 0.1143)
			(thermal_gap 0.1143)
			(padstack
				(mode front_inner_back)
				(layer "Inner"
					(shape circle)
					(size 0 0)
				)
				(layer "B.Cu"
					(shape circle)
					(size 0.3556 0.3556)
					(clearance 0.0889)
				)
			)
		)
		(pad "M14" smd circle
			(at 3.250006 2.250008 180)
			(size 0.254 0.254)
			(layers "F.Cu" "F.Mask" "F.Paste")
			(net "_NC_CPLD_16")
		)
		(pad "N1" smd circle
			(at -3.250006 2.750007 180)
			(size 0.254 0.254)
			(layers "F.Cu" "F.Mask" "F.Paste")
			(net "_NC_CPLD_5")
		)
		(pad "N2" smd circle
			(at -2.750007 2.750007 180)
			(size 0.254 0.254)
			(layers "F.Cu" "F.Mask" "F.Paste")
			(net "_NC_CPLD_8")
		)
		(pad "N3" thru_hole circle
			(at -2.250008 2.750007 180)
			(size 0.3048 0.3048)
			(drill 0.127)
			(layers "*.Cu" "*.Mask")
			(remove_unused_layers no)
			(net "NWK1_LED_LINK_G_L")
			(clearance 0.1143)
			(thermal_gap 0.1143)
			(padstack
				(mode front_inner_back)
				(layer "Inner"
					(shape circle)
					(size 0 0)
				)
				(layer "B.Cu"
					(shape circle)
					(size 0.3556 0.3556)
					(clearance 0.0889)
				)
			)
		)
		(pad "N4" thru_hole circle
			(at -1.750009 2.750007 180)
			(size 0.3048 0.3048)
			(drill 0.127)
			(layers "*.Cu" "*.Mask")
			(remove_unused_layers no)
			(net "NFP_SPI2_MISO")
			(clearance 0.1143)
			(thermal_gap 0.1143)
			(padstack
				(mode front_inner_back)
				(layer "Inner"
					(shape circle)
					(size 0 0)
				)
				(layer "B.Cu"
					(shape circle)
					(size 0.3556 0.3556)
					(clearance 0.0889)
				)
			)
		)
		(pad "N5" smd circle
			(at -1.25001 2.750007 180)
			(size 0.254 0.254)
			(layers "F.Cu" "F.Mask" "F.Paste")
			(net "_NC_CPLD_9")
		)
		(pad "N6" thru_hole circle
			(at -0.750011 2.750007 180)
			(size 0.3048 0.3048)
			(drill 0.127)
			(layers "*.Cu" "*.Mask")
			(remove_unused_layers no)
			(net "CPLD_SMBUS_SDA")
			(clearance 0.1143)
			(thermal_gap 0.1143)
			(padstack
				(mode front_inner_back)
				(layer "Inner"
					(shape circle)
					(size 0 0)
				)
				(layer "B.Cu"
					(shape circle)
					(size 0.3556 0.3556)
					(clearance 0.0889)
				)
			)
		)
		(pad "N7" smd circle
			(at -0.250012 2.750007 180)
			(size 0.254 0.254)
			(layers "F.Cu" "F.Mask" "F.Paste")
			(net "_NC_FAN_TACH")
		)
		(pad "N8" thru_hole circle
			(at 0.250012 2.750007 180)
			(size 0.3048 0.3048)
			(drill 0.127)
			(layers "*.Cu" "*.Mask")
			(remove_unused_layers no)
			(net "CPLD_VERSION_0")
			(clearance 0.1143)
			(thermal_gap 0.1143)
			(padstack
				(mode front_inner_back)
				(layer "Inner"
					(shape circle)
					(size 0 0)
				)
				(layer "B.Cu"
					(shape circle)
					(size 0.3556 0.3556)
					(clearance 0.0889)
				)
			)
		)
		(pad "N9" smd circle
			(at 0.750011 2.750007 180)
			(size 0.254 0.254)
			(layers "F.Cu" "F.Mask" "F.Paste")
			(net "_NC_CPLD_13")
		)
		(pad "N10" thru_hole circle
			(at 1.25001 2.750007 180)
			(size 0.3048 0.3048)
			(drill 0.127)
			(layers "*.Cu" "*.Mask")
			(remove_unused_layers no)
			(net "CPLD_VERSION_2")
			(clearance 0.1143)
			(thermal_gap 0.1143)
			(padstack
				(mode front_inner_back)
				(layer "Inner"
					(shape circle)
					(size 0 0)
				)
				(layer "B.Cu"
					(shape circle)
					(size 0.3556 0.3556)
					(clearance 0.0889)
				)
			)
		)
		(pad "N11" thru_hole circle
			(at 1.750009 2.750007 180)
			(size 0.3048 0.3048)
			(drill 0.127)
			(layers "*.Cu" "*.Mask")
			(remove_unused_layers no)
			(net "EXT_3.3V")
			(clearance 0.1143)
			(thermal_gap 0.1143)
			(padstack
				(mode front_inner_back)
				(layer "Inner"
					(shape circle)
					(size 0 0)
				)
				(layer "B.Cu"
					(shape circle)
					(size 0.3556 0.3556)
					(clearance 0.0889)
				)
			)
		)
		(pad "N12" thru_hole circle
			(at 2.250008 2.750007 180)
			(size 0.3048 0.3048)
			(drill 0.127)
			(layers "*.Cu" "*.Mask")
			(remove_unused_layers no)
			(net "CPLD_NIC_MEZZ_ID0")
			(clearance 0.1143)
			(thermal_gap 0.1143)
			(padstack
				(mode front_inner_back)
				(layer "Inner"
					(shape circle)
					(size 0 0)
				)
				(layer "B.Cu"
					(shape circle)
					(size 0.3556 0.3556)
					(clearance 0.0889)
				)
			)
		)
		(pad "N13" thru_hole circle
			(at 2.750007 2.750007 180)
			(size 0.3048 0.3048)
			(drill 0.127)
			(layers "*.Cu" "*.Mask")
			(remove_unused_layers no)
			(net "NFP_SRESET_L")
			(clearance 0.1143)
			(thermal_gap 0.1143)
			(padstack
				(mode front_inner_back)
				(layer "Inner"
					(shape circle)
					(size 0 0)
				)
				(layer "B.Cu"
					(shape circle)
					(size 0.3556 0.3556)
					(clearance 0.0889)
				)
			)
		)
		(pad "N14" smd circle
			(at 3.250006 2.750007 180)
			(size 0.254 0.254)
			(layers "F.Cu" "F.Mask" "F.Paste")
			(net "NFP_PGOOD4")
		)
		(pad "P1" smd circle
			(at -3.250006 3.250006 180)
			(size 0.254 0.254)
			(layers "F.Cu" "F.Mask" "F.Paste")
			(net "EXT_3.3V")
		)
		(pad "P2" smd circle
			(at -2.750007 3.250006 180)
			(size 0.254 0.254)
			(layers "F.Cu" "F.Mask" "F.Paste")
			(net "_NC_CPLD_7")
		)
		(pad "P3" smd circle
			(at -2.250008 3.250006 180)
			(size 0.254 0.254)
			(layers "F.Cu" "F.Mask" "F.Paste")
			(net "CPLD_GPIO_2")
		)
		(pad "P4" smd circle
			(at -1.750009 3.250006 180)
			(size 0.254 0.254)
			(layers "F.Cu" "F.Mask" "F.Paste")
			(net "CPLD_PCIE0_WAKE_L")
		)
		(pad "P5" smd circle
			(at -1.25001 3.250006 180)
			(size 0.254 0.254)
			(layers "F.Cu" "F.Mask" "F.Paste")
			(net "GND")
		)
		(pad "P6" smd circle
			(at -0.750011 3.250006 180)
			(size 0.254 0.254)
			(layers "F.Cu" "F.Mask" "F.Paste")
			(net "NFP_PCIE0_RESET_OUT_L")
		)
		(pad "P7" smd circle
			(at -0.250012 3.250006 180)
			(size 0.254 0.254)
			(layers "F.Cu" "F.Mask" "F.Paste")
			(net "CPLD_SMBUS_SCL")
		)
		(pad "P8" smd circle
			(at 0.250012 3.250006 180)
			(size 0.254 0.254)
			(layers "F.Cu" "F.Mask" "F.Paste")
			(net "CPLD_GPIO_0")
		)
		(pad "P9" smd circle
			(at 0.750011 3.250006 180)
			(size 0.254 0.254)
			(layers "F.Cu" "F.Mask" "F.Paste")
			(net "_NC_CPLD_12")
		)
		(pad "P10" smd circle
			(at 1.25001 3.250006 180)
			(size 0.254 0.254)
			(layers "F.Cu" "F.Mask" "F.Paste")
			(net "GND")
		)
		(pad "P11" smd circle
			(at 1.750009 3.250006 180)
			(size 0.254 0.254)
			(layers "F.Cu" "F.Mask" "F.Paste")
			(net "NFP_SPI2_CS")
		)
		(pad "P12" smd circle
			(at 2.250008 3.250006 180)
			(size 0.254 0.254)
			(layers "F.Cu" "F.Mask" "F.Paste")
			(net "_NC_CPLD_15")
		)
		(pad "P13" smd circle
			(at 2.750007 3.250006 180)
			(size 0.254 0.254)
			(layers "F.Cu" "F.Mask" "F.Paste")
			(net "NFP_SPI2_MOSI")
		)
		(pad "P14" smd circle
			(at 3.250006 3.250006 180)
			(size 0.254 0.254)
			(layers "F.Cu" "F.Mask" "F.Paste")
			(net "EXT_3.3V")
		)
	)
)
